# SCM (Grand Teton) — schematic netlist excerpt (pin names and nets, part order shuffled) for the footprints in the layout excerpt that follows; sources: Cadence DE-HDL packaged netlist, KiCad conversion of 12092022_DA0F0TMDCD0_F0T_Management_Board_D_brd_V3_OCP.brd

C90  Q_CAP  1UF 25V 10% X6S  pkg C0402  page 17 : A = P1V0_STBY_DP_VCC10A ; B = GND
R360  Q_RES  120 1% CHIP  pkg 0402LF  page 20 : A = M_BMC_DDR4_MA<9> ; B = P1V2_AUX

(kicad_pcb
	(version 20260206)
	(generator "pcbnew")
	(generator_version "10.0")
	(general
		(thickness 1.6)
		(legacy_teardrops no)
	)
	(paper "A4")
	(title_block
		(title "12092022_DA0F0TMDCD0_F0T_Management_Board_D_brd_V3_OCP.brd")
		(comment 1 "Grand Teton / footprints 1376-1377 of 1440")
	)
	(layers
		(0 "F.Cu" signal "TOP")
		(4 "In1.Cu" signal "GND")
		(6 "In2.Cu" signal "IN1")
		(8 "In3.Cu" signal "GND1")
		(10 "In4.Cu" signal "IN2")
		(12 "In5.Cu" signal "VCC")
		(14 "In6.Cu" signal "VCC1")
		(16 "In7.Cu" signal "IN3")
		(18 "In8.Cu" signal "GND2")
		(20 "In9.Cu" signal "IN4")
		(22 "In10.Cu" signal "GND3")
		(2 "B.Cu" signal "BOTTOM")
		(9 "F.Adhes" user "F.Adhesive")
		(11 "B.Adhes" user "B.Adhesive")
		(13 "F.Paste" user "Package Geometry/Pastemask Top")
		(15 "B.Paste" user "Package Geometry/Pastemask Bottom")
		(5 "F.SilkS" user "Ref Des/Silkscreen Top")
		(7 "B.SilkS" user "Ref Des/Silkscreen Bottom")
		(1 "F.Mask" user "Board Geometry/Soldermask Top")
		(3 "B.Mask" user "Board Geometry/Soldermask Bottom")
		(17 "Dwgs.User" user "User.Drawings")
		(19 "Cmts.User" user "User.Comments")
		(21 "Eco1.User" user "User.Eco1")
		(23 "Eco2.User" user "User.Eco2")
		(25 "Edge.Cuts" user "Board Geometry/Outline")
		(27 "Margin" user)
		(31 "F.CrtYd" user "Package Geometry/Place Bound Top")
		(29 "B.CrtYd" user "Package Geometry/Place Bound Bottom")
		(35 "F.Fab" user "Ref Des/Assembly Top")
		(33 "B.Fab" user "Ref Des/Assembly Bottom")
	)
	(footprint ""
		(layer "B.Cu")
		(at 75.528678 -59.618118 90)
		(property "Reference" "C90"
			(at 0 0 90)
			(layer "B.SilkS")
			(hide yes)
			(effects
				(font
					(size 1.27 1.27)
				)
				(justify mirror)
			)
		)
		(property "Value" ""
			(at 0 0 90)
			(layer "B.Fab")
			(effects
				(font
					(size 1.27 1.27)
				)
				(justify mirror)
			)
		)
		(duplicate_pad_numbers_are_jumpers no)
		(fp_line
			(start 0.7874 -0.4064)
			(end -0.7874 -0.4064)
			(stroke
				(width 0.1524)
				(type default)
			)
			(layer "B.SilkS")
		)
		(fp_line
			(start -0.7874 -0.4064)
			(end -0.7874 0.4064)
			(stroke
				(width 0.1524)
				(type default)
			)
			(layer "B.SilkS")
		)
		(fp_line
			(start 0.7874 0.4064)
			(end 0.7874 -0.4064)
			(stroke
				(width 0.1524)
				(type default)
			)
			(layer "B.SilkS")
		)
		(fp_line
			(start -0.7874 0.4064)
			(end 0.7874 0.4064)
			(stroke
				(width 0.1524)
				(type default)
			)
			(layer "B.SilkS")
		)
		(fp_line
			(start 0.67945 -0.305054)
			(end 0.12065 -0.305054)
			(stroke
				(width 0.1)
				(type default)
			)
			(layer "B.Fab")
		)
		(fp_line
			(start 0.12065 -0.305054)
			(end 0.12065 -0.2794)
			(stroke
				(width 0.1)
				(type default)
			)
			(layer "B.Fab")
		)
		(fp_line
			(start -0.12065 -0.3048)
			(end -0.67945 -0.3048)
			(stroke
				(width 0.1)
				(type default)
			)
			(layer "B.Fab")
		)
		(fp_line
			(start -0.67945 -0.3048)
			(end -0.67945 0.3048)
			(stroke
				(width 0.1)
				(type default)
			)
			(layer "B.Fab")
		)
		(fp_line
			(start 0.12065 -0.2794)
			(end -0.12065 -0.2794)
			(stroke
				(width 0.1)
				(type default)
			)
			(layer "B.Fab")
		)
		(fp_line
			(start -0.12065 -0.2794)
			(end -0.12065 -0.3048)
			(stroke
				(width 0.1)
				(type default)
			)
			(layer "B.Fab")
		)
		(fp_line
			(start 0.12065 0.2794)
			(end 0.12065 0.3048)
			(stroke
				(width 0.1)
				(type default)
			)
			(layer "B.Fab")
		)
		(fp_line
			(start -0.120396 0.2794)
			(end 0.12065 0.2794)
			(stroke
				(width 0.1)
				(type default)
			)
			(layer "B.Fab")
		)
		(fp_line
			(start 0.67945 0.3048)
			(end 0.67945 -0.305054)
			(stroke
				(width 0.1)
				(type default)
			)
			(layer "B.Fab")
		)
		(fp_line
			(start 0.12065 0.3048)
			(end 0.67945 0.3048)
			(stroke
				(width 0.1)
				(type default)
			)
			(layer "B.Fab")
		)
		(fp_line
			(start -0.120396 0.3048)
			(end -0.120396 0.2794)
			(stroke
				(width 0.1)
				(type default)
			)
			(layer "B.Fab")
		)
		(fp_line
			(start -0.67945 0.3048)
			(end -0.120396 0.3048)
			(stroke
				(width 0.1)
				(type default)
			)
			(layer "B.Fab")
		)
		(pad "1" smd circle
			(at 0.40005 0 270)
			(size 0 0)
			(layers "B.Cu" "B.Mask" "B.Paste")
			(net "P1V0_STBY_DP_VCC10A")
		)
		(pad "2" smd circle
			(at -0.40005 0 270)
			(size 0 0)
			(layers "B.Cu" "B.Mask" "B.Paste")
			(net "GND")
		)
	)
	(footprint ""
		(layer "B.Cu")
		(at 85.281262 -43.411394 180)
		(property "Reference" "R360"
			(at 0 0 0)
			(layer "B.SilkS")
			(hide yes)
			(effects
				(font
					(size 1.27 1.27)
				)
				(justify mirror)
			)
		)
		(property "Value" ""
			(at 0 0 0)
			(layer "B.Fab")
			(effects
				(font
					(size 1.27 1.27)
				)
				(justify mirror)
			)
		)
		(duplicate_pad_numbers_are_jumpers no)
		(fp_line
			(start 0.7874 0.4064)
			(end 0.7874 -0.4064)
			(stroke
				(width 0.1524)
				(type default)
			)
			(layer "B.SilkS")
		)
		(fp_line
			(start 0.7874 -0.4064)
			(end -0.7874 -0.4064)
			(stroke
				(width 0.1524)
				(type default)
			)
			(layer "B.SilkS")
		)
		(fp_line
			(start -0.7874 0.4064)
			(end 0.7874 0.4064)
			(stroke
				(width 0.1524)
				(type default)
			)
			(layer "B.SilkS")
		)
		(fp_line
			(start -0.7874 -0.4064)
			(end -0.7874 0.4064)
			(stroke
				(width 0.1524)
				(type default)
			)
			(layer "B.SilkS")
		)
		(fp_line
			(start 0.67945 0.3048)
			(end 0.67945 -0.305054)
			(stroke
				(width 0.1)
				(type default)
			)
			(layer "B.Fab")
		)
		(fp_line
			(start 0.67945 -0.305054)
			(end 0.12065 -0.305054)
			(stroke
				(width 0.1)
				(type default)
			)
			(layer "B.Fab")
		)
		(fp_line
			(start 0.12065 0.3048)
			(end 0.67945 0.3048)
			(stroke
				(width 0.1)
				(type default)
			)
			(layer "B.Fab")
		)
		(fp_line
			(start 0.12065 0.2794)
			(end 0.12065 0.3048)
			(stroke
				(width 0.1)
				(type default)
			)
			(layer "B.Fab")
		)
		(fp_line
			(start 0.12065 -0.2794)
			(end -0.12065 -0.2794)
			(stroke
				(width 0.1)
				(type default)
			)
			(layer "B.Fab")
		)
		(fp_line
			(start 0.12065 -0.305054)
			(end 0.12065 -0.2794)
			(stroke
				(width 0.1)
				(type default)
			)
			(layer "B.Fab")
		)
		(fp_line
			(start -0.120396 0.3048)
			(end -0.120396 0.2794)
			(stroke
				(width 0.1)
				(type default)
			)
			(layer "B.Fab")
		)
		(fp_line
			(start -0.120396 0.2794)
			(end 0.12065 0.2794)
			(stroke
				(width 0.1)
				(type default)
			)
			(layer "B.Fab")
		)
		(fp_line
			(start -0.12065 -0.2794)
			(end -0.12065 -0.3048)
			(stroke
				(width 0.1)
				(type default)
			)
			(layer "B.Fab")
		)
		(fp_line
			(start -0.12065 -0.3048)
			(end -0.67945 -0.3048)
			(stroke
				(width 0.1)
				(type default)
			)
			(layer "B.Fab")
		)
		(fp_line
			(start -0.67945 0.3048)
			(end -0.120396 0.3048)
			(stroke
				(width 0.1)
				(type default)
			)
			(layer "B.Fab")
		)
		(fp_line
			(start -0.67945 -0.3048)
			(end -0.67945 0.3048)
			(stroke
				(width 0.1)
				(type default)
			)
			(layer "B.Fab")
		)
		(pad "1" smd circle
			(at 0.40005 0)
			(size 0 0)
			(layers "B.Cu" "B.Mask" "B.Paste")
			(net "M_BMC_DDR4_MA<9>")
		)
		(pad "2" smd circle
			(at -0.40005 0)
			(size 0 0)
			(layers "B.Cu" "B.Mask" "B.Paste")
			(net "P1V2_AUX")
		)
	)
)
